# S9S_MB_2U (Grand Teton) — schematic netlist excerpt (pin names and nets, part order shuffled) for the footprints in the layout excerpt that follows; sources: Cadence DE-HDL packaged netlist, KiCad conversion of 03242023_DA0F0TMBIJ0_F0T_Motherboard_J_brd_V01_OCP.brd

C2344  Q_CAP  0.1UF 25V 10% X7R  pkg 0402  page 155 : A = P3V3_AUX ; B = GND

U102  INA183A1IDBVR  EMPTY  pkg SOT23-5_0-95_2-9X1-6XD  page 251
  GND0  = GND
  GND1  = GND
  \out\  = PVCCD_HV_CPU0_NVDIMM_ISENSE
  \in-\  = P12V_AUX_CPU0_DIMM_ISEN_N
  \in+\  = P12V_AUX_CPU0_DIMM_ISEN_P

(kicad_pcb
	(version 20260206)
	(generator "pcbnew")
	(generator_version "10.0")
	(general
		(thickness 1.6)
		(legacy_teardrops no)
	)
	(paper "A4")
	(title_block
		(title "03242023_DA0F0TMBIJ0_F0T_Motherboard_J_brd_V01_OCP.brd")
		(comment 1 "Grand Teton / footprints 1666-1667 of 6105")
	)
	(layers
		(0 "F.Cu" signal "TOP")
		(4 "In1.Cu" signal "GND")
		(6 "In2.Cu" signal "IN1")
		(8 "In3.Cu" signal "GND1")
		(10 "In4.Cu" signal "IN2")
		(12 "In5.Cu" signal "GND2")
		(14 "In6.Cu" signal "IN3")
		(16 "In7.Cu" signal "GND3")
		(18 "In8.Cu" signal "VCC")
		(20 "In9.Cu" signal "VCC1")
		(22 "In10.Cu" signal "GND4")
		(24 "In11.Cu" signal "IN4")
		(26 "In12.Cu" signal "GND5")
		(28 "In13.Cu" signal "IN5")
		(30 "In14.Cu" signal "GND6")
		(32 "In15.Cu" signal "IN6")
		(34 "In16.Cu" signal "GND7")
		(2 "B.Cu" signal "BOTTOM")
		(9 "F.Adhes" user "F.Adhesive")
		(11 "B.Adhes" user "B.Adhesive")
		(13 "F.Paste" user "Package Geometry/Pastemask Top")
		(15 "B.Paste" user "Package Geometry/Pastemask Bottom")
		(5 "F.SilkS" user "Ref Des/Silkscreen Top")
		(7 "B.SilkS" user "Ref Des/Silkscreen Bottom")
		(1 "F.Mask" user "Board Geometry/Soldermask Top")
		(3 "B.Mask" user "Board Geometry/Soldermask Bottom")
		(17 "Dwgs.User" user "User.Drawings")
		(19 "Cmts.User" user "User.Comments")
		(21 "Eco1.User" user "User.Eco1")
		(23 "Eco2.User" user "User.Eco2")
		(25 "Edge.Cuts" user "Board Geometry/Outline")
		(27 "Margin" user)
		(31 "F.CrtYd" user "Package Geometry/Place Bound Top")
		(29 "B.CrtYd" user "Package Geometry/Place Bound Bottom")
		(35 "F.Fab" user "Ref Des/Assembly Top")
		(33 "B.Fab" user "Ref Des/Assembly Bottom")
	)
	(footprint ""
		(layer "F.Cu")
		(at 92.7608 -33.061148)
		(property "Reference" "C2344"
			(at 0 0 0)
			(layer "F.SilkS")
			(hide yes)
			(effects
				(font
					(size 1.27 1.27)
				)
			)
		)
		(property "Value" ""
			(at 0 0 0)
			(layer "F.Fab")
			(effects
				(font
					(size 1.27 1.27)
				)
			)
		)
		(duplicate_pad_numbers_are_jumpers no)
		(fp_line
			(start -0.7874 -0.4064)
			(end 0.7874 -0.4064)
			(stroke
				(width 0.1524)
				(type default)
			)
			(layer "F.SilkS")
		)
		(fp_line
			(start -0.7874 0.4064)
			(end -0.7874 -0.4064)
			(stroke
				(width 0.1524)
				(type default)
			)
			(layer "F.SilkS")
		)
		(fp_line
			(start 0.7874 -0.4064)
			(end 0.7874 0.4064)
			(stroke
				(width 0.1524)
				(type default)
			)
			(layer "F.SilkS")
		)
		(fp_line
			(start 0.7874 0.4064)
			(end -0.7874 0.4064)
			(stroke
				(width 0.1524)
				(type default)
			)
			(layer "F.SilkS")
		)
		(fp_line
			(start -0.67945 -0.305054)
			(end -0.12065 -0.305054)
			(stroke
				(width 0.1)
				(type default)
			)
			(layer "F.Fab")
		)
		(fp_line
			(start -0.67945 0.3048)
			(end -0.67945 -0.305054)
			(stroke
				(width 0.1)
				(type default)
			)
			(layer "F.Fab")
		)
		(fp_line
			(start -0.12065 -0.305054)
			(end -0.12065 -0.2794)
			(stroke
				(width 0.1)
				(type default)
			)
			(layer "F.Fab")
		)
		(fp_line
			(start -0.12065 -0.2794)
			(end 0.12065 -0.2794)
			(stroke
				(width 0.1)
				(type default)
			)
			(layer "F.Fab")
		)
		(fp_line
			(start -0.12065 0.2794)
			(end -0.12065 0.3048)
			(stroke
				(width 0.1)
				(type default)
			)
			(layer "F.Fab")
		)
		(fp_line
			(start -0.12065 0.3048)
			(end -0.67945 0.3048)
			(stroke
				(width 0.1)
				(type default)
			)
			(layer "F.Fab")
		)
		(fp_line
			(start 0.120396 0.2794)
			(end -0.12065 0.2794)
			(stroke
				(width 0.1)
				(type default)
			)
			(layer "F.Fab")
		)
		(fp_line
			(start 0.120396 0.3048)
			(end 0.120396 0.2794)
			(stroke
				(width 0.1)
				(type default)
			)
			(layer "F.Fab")
		)
		(fp_line
			(start 0.12065 -0.3048)
			(end 0.67945 -0.3048)
			(stroke
				(width 0.1)
				(type default)
			)
			(layer "F.Fab")
		)
		(fp_line
			(start 0.12065 -0.2794)
			(end 0.12065 -0.3048)
			(stroke
				(width 0.1)
				(type default)
			)
			(layer "F.Fab")
		)
		(fp_line
			(start 0.67945 -0.3048)
			(end 0.67945 0.3048)
			(stroke
				(width 0.1)
				(type default)
			)
			(layer "F.Fab")
		)
		(fp_line
			(start 0.67945 0.3048)
			(end 0.120396 0.3048)
			(stroke
				(width 0.1)
				(type default)
			)
			(layer "F.Fab")
		)
		(pad "1" smd circle
			(at -0.40005 0)
			(size 0 0)
			(layers "F.Cu" "F.Mask" "F.Paste")
			(net "P3V3_AUX")
		)
		(pad "2" smd circle
			(at 0.40005 0)
			(size 0 0)
			(layers "F.Cu" "F.Mask" "F.Paste")
			(net "GND")
		)
	)
	(footprint ""
		(layer "F.Cu")
		(at 444.039498 -335.221072)
		(property "Reference" "U102"
			(at -0.5207 -2.466848 0)
			(unlocked yes)
			(layer "F.SilkS")
			(effects
				(font
					(size 0.7874 0.5842)
					(thickness 0.1524)
				)
				(justify left)
			)
		)
		(property "Value" ""
			(at 0 0 0)
			(layer "F.Fab")
			(effects
				(font
					(size 1.27 1.27)
				)
			)
		)
		(duplicate_pad_numbers_are_jumpers no)
		(fp_line
			(start -1.99263 -1.525016)
			(end -1.99263 1.525016)
			(stroke
				(width 0.1524)
				(type default)
			)
			(layer "F.SilkS")
		)
		(fp_line
			(start -1.99263 1.525016)
			(end 1.99263 1.525016)
			(stroke
				(width 0.1524)
				(type default)
			)
			(layer "F.SilkS")
		)
		(fp_line
			(start 1.99263 -1.525016)
			(end -1.99263 -1.525016)
			(stroke
				(width 0.1524)
				(type default)
			)
			(layer "F.SilkS")
		)
		(fp_line
			(start 1.99263 1.525016)
			(end 1.99263 -1.525016)
			(stroke
				(width 0.1524)
				(type default)
			)
			(layer "F.SilkS")
		)
		(fp_poly
			(pts
				(xy -0.843534 -2.815082) (xy -1.351534 -1.799082) (xy -1.859534 -2.815082)
			)
			(stroke
				(width 0)
				(type default)
			)
			(fill yes)
			(layer "F.SilkS")
		)
		(fp_line
			(start -0.87503 -1.525016)
			(end -0.87503 1.525016)
			(stroke
				(width 0.1)
				(type default)
			)
			(layer "F.Fab")
		)
		(fp_line
			(start -0.87503 1.525016)
			(end 0.87503 1.525016)
			(stroke
				(width 0.1)
				(type default)
			)
			(layer "F.Fab")
		)
		(fp_line
			(start 0.87503 -1.525016)
			(end -0.87503 -1.525016)
			(stroke
				(width 0.1)
				(type default)
			)
			(layer "F.Fab")
		)
		(fp_line
			(start 0.87503 1.525016)
			(end 0.87503 -1.525016)
			(stroke
				(width 0.1)
				(type default)
			)
			(layer "F.Fab")
		)
		(fp_poly
			(pts
				(xy -3.2004 -1.45796) (xy -3.2004 -0.44196) (xy -2.1844 -0.94996)
			)
			(stroke
				(width 0)
				(type default)
			)
			(fill yes)
			(layer "F.Fab")
		)
		(pad "1" smd circle
			(at -1.299972 -0.94996 270)
			(size 0 0)
			(layers "F.Cu" "F.Mask" "F.Paste")
			(net "GND")
		)
		(pad "2" smd circle
			(at -1.299972 0 270)
			(size 0 0)
			(layers "F.Cu" "F.Mask" "F.Paste")
			(net "GND")
		)
		(pad "3" smd circle
			(at -1.299972 0.94996 270)
			(size 0 0)
			(layers "F.Cu" "F.Mask" "F.Paste")
			(net "PVCCD_HV_CPU0_NVDIMM_ISENSE")
		)
		(pad "4" smd circle
			(at 1.299972 0.94996 270)
			(size 0 0)
			(layers "F.Cu" "F.Mask" "F.Paste")
			(net "P12V_AUX_CPU0_DIMM_ISEN_N")
		)
		(pad "5" smd circle
			(at 1.299972 -0.94996 270)
			(size 0 0)
			(layers "F.Cu" "F.Mask" "F.Paste")
			(net "P12V_AUX_CPU0_DIMM_ISEN_P")
		)
	)
)
